FILE_TYPE=LIBRARY_PARTS;
primitive 'LT6700CS61TRPBF';
  pin
    'VS':
      PIN_NUMBER='(5)';
      PINUSE='POWER';
      NO_LOAD_CHECK='Both';
      NO_IO_CHECK='Both';
      NO_ASSERT_CHECK='TRUE';
      NO_DIR_CHECK='TRUE';
      ALLOW_CONNECT='TRUE';
    'INB-':
      PIN_NUMBER='(4)';
      INPUT_LOAD='(-0.01,0.01)';
    'GND':
      PIN_NUMBER='(2)';
      PINUSE='POWER';
      NO_LOAD_CHECK='Both';
      NO_IO_CHECK='Both';
      NO_ASSERT_CHECK='TRUE';
      NO_DIR_CHECK='TRUE';
      ALLOW_CONNECT='TRUE';
    'OUTA':
      PIN_NUMBER='(1)';
      OUTPUT_LOAD='(1.0,-1.0)';
    'INA+':
      PIN_NUMBER='(3)';
      INPUT_LOAD='(-0.01,0.01)';
    'OUTB':
      PIN_NUMBER='(6)';
      OUTPUT_LOAD='(1.0,-1.0)';
  end_pin;
  body
    PART_NAME='LT6700CS61TRPBF';
    BODY_NAME='LT6700CS61TRPBF';
    PHYS_DES_PREFIX='U';
    CLASS='IC';
  end_body;
end_primitive;

END.
